# TIMECARD (Time Appliance Project (Time Card)) — schematic netlist excerpt (pin names and nets, part order shuffled) for the footprints in the layout excerpt that follows; sources: Cadence DE-HDL packaged netlist, KiCad conversion of R4006-B0001-02_R01.brd

Y2  XTAL_4  pkg SMC_Y4_126X098_V5_H032  page 24
  \1\  = UNNAMED_524_CAPACITOR_I7_2
  \2\  = SG
  \3\  = UNNAMED_524_CAPACITOR_I10_2
  \4\  = SG

(kicad_pcb
	(version 20260206)
	(generator "pcbnew")
	(generator_version "10.0")
	(general
		(thickness 1.6)
		(legacy_teardrops no)
	)
	(paper "A4")
	(title_block
		(title "timecard-production-celestica-r4006 — R4006-B0001-02_R01.brd")
		(comment 1 "Time Appliance Project (Time Card) / footprints 597-597 of 1113")
	)
	(layers
		(0 "F.Cu" signal "TOP")
		(4 "In1.Cu" signal "L02_GND1")
		(6 "In2.Cu" signal "L03_SIG1")
		(8 "In3.Cu" signal "L04_GND2")
		(10 "In4.Cu" signal "L05_VCC1")
		(12 "In5.Cu" signal "L06_VCC2")
		(14 "In6.Cu" signal "L07_GND3")
		(16 "In7.Cu" signal "L08_SIG2")
		(18 "In8.Cu" signal "L09_GND4")
		(2 "B.Cu" signal "BOTTOM")
		(9 "F.Adhes" user "F.Adhesive")
		(11 "B.Adhes" user "B.Adhesive")
		(13 "F.Paste" user "Package Geometry/Pastemask Top")
		(15 "B.Paste" user "Package Geometry/Pastemask Bottom")
		(5 "F.SilkS" user "Ref Des/Silkscreen Top")
		(7 "B.SilkS" user "Ref Des/Silkscreen Bottom")
		(1 "F.Mask" user "Board Geometry/Soldermask Top")
		(3 "B.Mask" user "Board Geometry/Soldermask Bottom")
		(17 "Dwgs.User" user "User.Drawings")
		(19 "Cmts.User" user "User.Comments")
		(21 "Eco1.User" user "User.Eco1")
		(23 "Eco2.User" user "User.Eco2")
		(25 "Edge.Cuts" user "Board Geometry/Outline")
		(27 "Margin" user)
		(31 "F.CrtYd" user "Package Geometry/Place Bound Top")
		(29 "B.CrtYd" user "Package Geometry/Place Bound Bottom")
		(35 "F.Fab" user "Ref Des/Assembly Top")
		(33 "B.Fab" user "Ref Des/Assembly Bottom")
	)
	(footprint ""
		(layer "F.Cu")
		(at 31.877 -98.679 180)
		(property "Reference" "Y2"
			(at 1.143 3.13563 0)
			(unlocked yes)
			(layer "F.SilkS")
			(effects
				(font
					(size 0.7874 0.5842)
					(thickness 0.1524)
				)
			)
		)
		(property "Value" ""
			(at 0 0 180)
			(layer "F.Fab")
			(effects
				(font
					(size 1.27 1.27)
				)
			)
		)
		(property "User Part Number" "PARTNUM*"
			(at 0.009906 4.56819 180)
			(unlocked yes)
			(layer "Cmts.User")
			(hide yes)
			(effects
				(font
					(size 0.7874 0.5842)
					(thickness 0.1524)
				)
			)
		)
		(property "Device Type" "XTAL_4-G131-10038-02"
			(at 0.009906 3.37439 180)
			(unlocked yes)
			(layer "F.Fab")
			(hide yes)
			(effects
				(font
					(size 0.7874 0.5842)
					(thickness 0.1524)
				)
			)
		)
		(duplicate_pad_numbers_are_jumpers no)
		(fp_line
			(start 2.052574 1.700784)
			(end -2.052574 1.700784)
			(stroke
				(width 0.1)
				(type default)
			)
			(layer "F.SilkS")
		)
		(fp_line
			(start 2.052574 -1.700784)
			(end 2.052574 1.700784)
			(stroke
				(width 0.1)
				(type default)
			)
			(layer "F.SilkS")
		)
		(fp_line
			(start -2.052574 1.700784)
			(end -2.052574 -1.700784)
			(stroke
				(width 0.1)
				(type default)
			)
			(layer "F.SilkS")
		)
		(fp_line
			(start -2.052574 -1.700784)
			(end 2.052574 -1.700784)
			(stroke
				(width 0.1)
				(type default)
			)
			(layer "F.SilkS")
		)
		(fp_poly
			(pts
				(arc
					(start -1.799336 2.413)
					(mid -1.037336 2.413)
					(end -1.799336 2.413)
				)
			)
			(stroke
				(width 0)
				(type default)
			)
			(fill yes)
			(layer "F.SilkS")
		)
		(fp_rect
			(start 2.306574 1.954784)
			(end -2.306574 -1.954784)
			(stroke
				(width 0)
				(type default)
			)
			(fill no)
			(layer "F.CrtYd")
		)
		(fp_line
			(start 1.649984 1.299972)
			(end -1.649984 1.299972)
			(stroke
				(width 0.1)
				(type default)
			)
			(layer "F.Fab")
		)
		(fp_line
			(start 1.649984 -1.299972)
			(end 1.649984 1.299972)
			(stroke
				(width 0.1)
				(type default)
			)
			(layer "F.Fab")
		)
		(fp_line
			(start -1.649984 1.299972)
			(end -1.649984 -1.299972)
			(stroke
				(width 0.1)
				(type default)
			)
			(layer "F.Fab")
		)
		(fp_line
			(start -1.649984 -1.299972)
			(end 1.649984 -1.299972)
			(stroke
				(width 0.1)
				(type default)
			)
			(layer "F.Fab")
		)
		(fp_poly
			(pts
				(arc
					(start -1.799336 2.032)
					(mid -1.037336 2.032)
					(end -1.799336 2.032)
				)
			)
			(stroke
				(width 0)
				(type default)
			)
			(fill yes)
			(layer "F.Fab")
		)
		(fp_text user "2"
			(at 2.667 2.62763 0)
			(unlocked yes)
			(layer "F.SilkS")
			(effects
				(font
					(size 0.7874 0.5842)
					(thickness 0.1524)
				)
			)
		)
		(fp_text user "3"
			(at 2.54 -2.07137 0)
			(unlocked yes)
			(layer "F.SilkS")
			(effects
				(font
					(size 0.7874 0.5842)
					(thickness 0.1524)
				)
			)
		)
		(fp_text user "4"
			(at -2.667 -2.07137 0)
			(unlocked yes)
			(layer "F.SilkS")
			(effects
				(font
					(size 0.7874 0.5842)
					(thickness 0.1524)
				)
			)
		)
		(fp_text user "3"
			(at 2.286 -1.43637 0)
			(unlocked yes)
			(layer "F.Fab")
			(effects
				(font
					(size 0.7874 0.5842)
					(thickness 0.1524)
				)
			)
		)
		(fp_text user "2"
			(at 2.159 1.99263 0)
			(unlocked yes)
			(layer "F.Fab")
			(effects
				(font
					(size 0.7874 0.5842)
					(thickness 0.1524)
				)
			)
		)
		(fp_text user "4"
			(at -2.413 -1.30937 0)
			(unlocked yes)
			(layer "F.Fab")
			(effects
				(font
					(size 0.7874 0.5842)
					(thickness 0.1524)
				)
			)
		)
		(pad "1" smd rect
			(at -1.100074 0.849884 180)
			(size 1.397 1.1938)
			(layers "F.Cu" "F.Mask" "F.Paste")
			(net "UNNAMED_524_CAPACITOR_I7_2")
		)
		(pad "2" smd rect
			(at 1.100074 0.849884 180)
			(size 1.397 1.1938)
			(layers "F.Cu" "F.Mask" "F.Paste")
			(net "SG")
		)
		(pad "3" smd rect
			(at 1.100074 -0.849884 180)
			(size 1.397 1.1938)
			(layers "F.Cu" "F.Mask" "F.Paste")
			(net "UNNAMED_524_CAPACITOR_I10_2")
		)
		(pad "4" smd rect
			(at -1.100074 -0.849884 180)
			(size 1.397 1.1938)
			(layers "F.Cu" "F.Mask" "F.Paste")
			(net "SG")
		)
		(zone
			(layer "F.Cu")
			(hatch none 0.5)
			(connect_pads
				(clearance 0)
			)
			(min_thickness 0.25)
			(keepout
				(tracks allowed)
				(vias not_allowed)
				(pads allowed)
				(copperpour not_allowed)
				(footprints allowed)
			)
			(placement
				(enabled no)
				(sheetname "")
			)
			(fill
				(thermal_gap 0.5)
				(thermal_bridge_width 0.5)
				(island_removal_mode 0)
			)
			(polygon
				(pts
					(xy 32.278574 -99.978972) (xy 32.278574 -98.931984) (xy 33.526984 -98.931984) (xy 33.526984 -98.426016)
					(xy 32.278574 -98.426016) (xy 32.278574 -97.379028) (xy 31.475426 -97.379028) (xy 31.475426 -98.426016)
					(xy 30.227016 -98.426016) (xy 30.227016 -98.931984) (xy 31.475426 -98.931984) (xy 31.475426 -99.978972)
				)
			)
		)
	)
)
